# T6G (Grand Teton) — schematic netlist excerpt (pin names and nets, part order shuffled) for the footprints in the layout excerpt that follows; sources: Cadence DE-HDL packaged netlist, KiCad conversion of 04192023_DAF0TMB3IC0_F0TG_MB_C_brd_V02_OCP.brd

C122  Q_CAP  4.7UF 6.3V 20% X6S  pkg 0402  page 323 : A = P1V8_CPU1_RT_1D ; B = GND
C2488  Q_CAP  22UF 4V 20% X6S  pkg C0402  page 74 : A = PVDD11_S3_P1 ; B = GND

(kicad_pcb
	(version 20260206)
	(generator "pcbnew")
	(generator_version "10.0")
	(general
		(thickness 1.6)
		(legacy_teardrops no)
	)
	(paper "A4")
	(title_block
		(title "04192023_DAF0TMB3IC0_F0TG_MB_C_brd_V02_OCP.brd")
		(comment 1 "Grand Teton / footprints 5036-5037 of 8354")
	)
	(layers
		(0 "F.Cu" signal "TOP")
		(4 "In1.Cu" signal "GND")
		(6 "In2.Cu" signal "IN1")
		(8 "In3.Cu" signal "GND1")
		(10 "In4.Cu" signal "IN2")
		(12 "In5.Cu" signal "GND2")
		(14 "In6.Cu" signal "IN3")
		(16 "In7.Cu" signal "GND3")
		(18 "In8.Cu" signal "VCC")
		(20 "In9.Cu" signal "VCC1")
		(22 "In10.Cu" signal "GND4")
		(24 "In11.Cu" signal "IN4")
		(26 "In12.Cu" signal "GND5")
		(28 "In13.Cu" signal "IN5")
		(30 "In14.Cu" signal "GND6")
		(32 "In15.Cu" signal "IN6")
		(34 "In16.Cu" signal "GND7")
		(2 "B.Cu" signal "BOTTOM")
		(9 "F.Adhes" user "F.Adhesive")
		(11 "B.Adhes" user "B.Adhesive")
		(13 "F.Paste" user "Package Geometry/Pastemask Top")
		(15 "B.Paste" user "Package Geometry/Pastemask Bottom")
		(5 "F.SilkS" user "Ref Des/Silkscreen Top")
		(7 "B.SilkS" user "Ref Des/Silkscreen Bottom")
		(1 "F.Mask" user "Board Geometry/Soldermask Top")
		(3 "B.Mask" user "Board Geometry/Soldermask Bottom")
		(17 "Dwgs.User" user "User.Drawings")
		(19 "Cmts.User" user "User.Comments")
		(21 "Eco1.User" user "User.Eco1")
		(23 "Eco2.User" user "User.Eco2")
		(25 "Edge.Cuts" user "Board Geometry/Outline")
		(27 "Margin" user)
		(31 "F.CrtYd" user "Package Geometry/Place Bound Top")
		(29 "B.CrtYd" user "Package Geometry/Place Bound Bottom")
		(35 "F.Fab" user "Ref Des/Assembly Top")
		(33 "B.Fab" user "Ref Des/Assembly Bottom")
	)
	(footprint ""
		(layer "B.Cu")
		(at 115.70589 -259.845302 180)
		(property "Reference" "C2488"
			(at 0 0 0)
			(layer "B.SilkS")
			(hide yes)
			(effects
				(font
					(size 1.27 1.27)
				)
				(justify mirror)
			)
		)
		(property "Value" ""
			(at 0 0 0)
			(layer "B.Fab")
			(effects
				(font
					(size 1.27 1.27)
				)
				(justify mirror)
			)
		)
		(duplicate_pad_numbers_are_jumpers no)
		(fp_line
			(start 0.7874 0.4064)
			(end 0.7874 -0.4064)
			(stroke
				(width 0.1524)
				(type default)
			)
			(layer "B.SilkS")
		)
		(fp_line
			(start 0.7874 -0.4064)
			(end -0.7874 -0.4064)
			(stroke
				(width 0.1524)
				(type default)
			)
			(layer "B.SilkS")
		)
		(fp_line
			(start -0.7874 0.4064)
			(end 0.7874 0.4064)
			(stroke
				(width 0.1524)
				(type default)
			)
			(layer "B.SilkS")
		)
		(fp_line
			(start -0.7874 -0.4064)
			(end -0.7874 0.4064)
			(stroke
				(width 0.1524)
				(type default)
			)
			(layer "B.SilkS")
		)
		(fp_line
			(start 0.67945 0.3048)
			(end 0.67945 -0.305054)
			(stroke
				(width 0.1)
				(type default)
			)
			(layer "B.Fab")
		)
		(fp_line
			(start 0.67945 -0.305054)
			(end 0.12065 -0.305054)
			(stroke
				(width 0.1)
				(type default)
			)
			(layer "B.Fab")
		)
		(fp_line
			(start 0.12065 0.3048)
			(end 0.67945 0.3048)
			(stroke
				(width 0.1)
				(type default)
			)
			(layer "B.Fab")
		)
		(fp_line
			(start 0.12065 0.2794)
			(end 0.12065 0.3048)
			(stroke
				(width 0.1)
				(type default)
			)
			(layer "B.Fab")
		)
		(fp_line
			(start 0.12065 -0.2794)
			(end -0.12065 -0.2794)
			(stroke
				(width 0.1)
				(type default)
			)
			(layer "B.Fab")
		)
		(fp_line
			(start 0.12065 -0.305054)
			(end 0.12065 -0.2794)
			(stroke
				(width 0.1)
				(type default)
			)
			(layer "B.Fab")
		)
		(fp_line
			(start -0.120396 0.3048)
			(end -0.120396 0.2794)
			(stroke
				(width 0.1)
				(type default)
			)
			(layer "B.Fab")
		)
		(fp_line
			(start -0.120396 0.2794)
			(end 0.12065 0.2794)
			(stroke
				(width 0.1)
				(type default)
			)
			(layer "B.Fab")
		)
		(fp_line
			(start -0.12065 -0.2794)
			(end -0.12065 -0.3048)
			(stroke
				(width 0.1)
				(type default)
			)
			(layer "B.Fab")
		)
		(fp_line
			(start -0.12065 -0.3048)
			(end -0.67945 -0.3048)
			(stroke
				(width 0.1)
				(type default)
			)
			(layer "B.Fab")
		)
		(fp_line
			(start -0.67945 0.3048)
			(end -0.120396 0.3048)
			(stroke
				(width 0.1)
				(type default)
			)
			(layer "B.Fab")
		)
		(fp_line
			(start -0.67945 -0.3048)
			(end -0.67945 0.3048)
			(stroke
				(width 0.1)
				(type default)
			)
			(layer "B.Fab")
		)
		(pad "1" smd circle
			(at 0.40005 0)
			(size 0 0)
			(layers "B.Cu" "B.Mask" "B.Paste")
			(net "PVDD11_S3_P1")
		)
		(pad "2" smd circle
			(at -0.40005 0)
			(size 0 0)
			(layers "B.Cu" "B.Mask" "B.Paste")
			(net "GND")
		)
	)
	(footprint ""
		(layer "B.Cu")
		(at 72.052434 -386.745988 -90)
		(property "Reference" "C122"
			(at 0 0 90)
			(layer "B.SilkS")
			(hide yes)
			(effects
				(font
					(size 1.27 1.27)
				)
				(justify mirror)
			)
		)
		(property "Value" ""
			(at 0 0 90)
			(layer "B.Fab")
			(effects
				(font
					(size 1.27 1.27)
				)
				(justify mirror)
			)
		)
		(duplicate_pad_numbers_are_jumpers no)
		(fp_line
			(start -0.7874 0.4064)
			(end 0.7874 0.4064)
			(stroke
				(width 0.1524)
				(type default)
			)
			(layer "B.SilkS")
		)
		(fp_line
			(start 0.7874 0.4064)
			(end 0.7874 -0.4064)
			(stroke
				(width 0.1524)
				(type default)
			)
			(layer "B.SilkS")
		)
		(fp_line
			(start -0.7874 -0.4064)
			(end -0.7874 0.4064)
			(stroke
				(width 0.1524)
				(type default)
			)
			(layer "B.SilkS")
		)
		(fp_line
			(start 0.7874 -0.4064)
			(end -0.7874 -0.4064)
			(stroke
				(width 0.1524)
				(type default)
			)
			(layer "B.SilkS")
		)
		(fp_line
			(start -0.67945 0.3048)
			(end -0.120396 0.3048)
			(stroke
				(width 0.1)
				(type default)
			)
			(layer "B.Fab")
		)
		(fp_line
			(start -0.120396 0.3048)
			(end -0.120396 0.2794)
			(stroke
				(width 0.1)
				(type default)
			)
			(layer "B.Fab")
		)
		(fp_line
			(start 0.12065 0.3048)
			(end 0.67945 0.3048)
			(stroke
				(width 0.1)
				(type default)
			)
			(layer "B.Fab")
		)
		(fp_line
			(start 0.67945 0.3048)
			(end 0.67945 -0.305054)
			(stroke
				(width 0.1)
				(type default)
			)
			(layer "B.Fab")
		)
		(fp_line
			(start -0.120396 0.2794)
			(end 0.12065 0.2794)
			(stroke
				(width 0.1)
				(type default)
			)
			(layer "B.Fab")
		)
		(fp_line
			(start 0.12065 0.2794)
			(end 0.12065 0.3048)
			(stroke
				(width 0.1)
				(type default)
			)
			(layer "B.Fab")
		)
		(fp_line
			(start -0.12065 -0.2794)
			(end -0.12065 -0.3048)
			(stroke
				(width 0.1)
				(type default)
			)
			(layer "B.Fab")
		)
		(fp_line
			(start 0.12065 -0.2794)
			(end -0.12065 -0.2794)
			(stroke
				(width 0.1)
				(type default)
			)
			(layer "B.Fab")
		)
		(fp_line
			(start -0.67945 -0.3048)
			(end -0.67945 0.3048)
			(stroke
				(width 0.1)
				(type default)
			)
			(layer "B.Fab")
		)
		(fp_line
			(start -0.12065 -0.3048)
			(end -0.67945 -0.3048)
			(stroke
				(width 0.1)
				(type default)
			)
			(layer "B.Fab")
		)
		(fp_line
			(start 0.12065 -0.305054)
			(end 0.12065 -0.2794)
			(stroke
				(width 0.1)
				(type default)
			)
			(layer "B.Fab")
		)
		(fp_line
			(start 0.67945 -0.305054)
			(end 0.12065 -0.305054)
			(stroke
				(width 0.1)
				(type default)
			)
			(layer "B.Fab")
		)
		(pad "1" smd circle
			(at 0.40005 0 90)
			(size 0 0)
			(layers "B.Cu" "B.Mask" "B.Paste")
			(net "P1V8_CPU1_RT_1D")
		)
		(pad "2" smd circle
			(at -0.40005 0 90)
			(size 0 0)
			(layers "B.Cu" "B.Mask" "B.Paste")
			(net "GND")
		)
	)
)
